# T6G (Grand Teton) — schematic netlist excerpt (pin names and nets, part order shuffled) for the footprints in the layout excerpt that follows; sources: Cadence DE-HDL packaged netlist, KiCad conversion of 04192023_DAF0TMB3IC0_F0TG_MB_C_brd_V02_OCP.brd

C2562  Q_CAP  22UF 4V 20% X6S  pkg C0402  page 70 : A = PVDDCR_SOC_P0 ; B = GND
R3688  Q_RES  0 5% CHIP  pkg 0402LF  page 257 : A = P1V581_PDB_ADC ; B = P3V3_PDB_AUX_ADC_TIC

(kicad_pcb
	(version 20260206)
	(generator "pcbnew")
	(generator_version "10.0")
	(general
		(thickness 1.6)
		(legacy_teardrops no)
	)
	(paper "A4")
	(title_block
		(title "04192023_DAF0TMB3IC0_F0TG_MB_C_brd_V02_OCP.brd")
		(comment 1 "Grand Teton / footprints 2273-2274 of 8354")
	)
	(layers
		(0 "F.Cu" signal "TOP")
		(4 "In1.Cu" signal "GND")
		(6 "In2.Cu" signal "IN1")
		(8 "In3.Cu" signal "GND1")
		(10 "In4.Cu" signal "IN2")
		(12 "In5.Cu" signal "GND2")
		(14 "In6.Cu" signal "IN3")
		(16 "In7.Cu" signal "GND3")
		(18 "In8.Cu" signal "VCC")
		(20 "In9.Cu" signal "VCC1")
		(22 "In10.Cu" signal "GND4")
		(24 "In11.Cu" signal "IN4")
		(26 "In12.Cu" signal "GND5")
		(28 "In13.Cu" signal "IN5")
		(30 "In14.Cu" signal "GND6")
		(32 "In15.Cu" signal "IN6")
		(34 "In16.Cu" signal "GND7")
		(2 "B.Cu" signal "BOTTOM")
		(9 "F.Adhes" user "F.Adhesive")
		(11 "B.Adhes" user "B.Adhesive")
		(13 "F.Paste" user "Package Geometry/Pastemask Top")
		(15 "B.Paste" user "Package Geometry/Pastemask Bottom")
		(5 "F.SilkS" user "Ref Des/Silkscreen Top")
		(7 "B.SilkS" user "Ref Des/Silkscreen Bottom")
		(1 "F.Mask" user "Board Geometry/Soldermask Top")
		(3 "B.Mask" user "Board Geometry/Soldermask Bottom")
		(17 "Dwgs.User" user "User.Drawings")
		(19 "Cmts.User" user "User.Comments")
		(21 "Eco1.User" user "User.Eco1")
		(23 "Eco2.User" user "User.Eco2")
		(25 "Edge.Cuts" user "Board Geometry/Outline")
		(27 "Margin" user)
		(31 "F.CrtYd" user "Package Geometry/Place Bound Top")
		(29 "B.CrtYd" user "Package Geometry/Place Bound Bottom")
		(35 "F.Fab" user "Ref Des/Assembly Top")
		(33 "B.Fab" user "Ref Des/Assembly Bottom")
	)
	(footprint ""
		(layer "F.Cu")
		(at 322.837048 -40.144954 180)
		(property "Reference" "R3688"
			(at 0 0 180)
			(layer "F.SilkS")
			(hide yes)
			(effects
				(font
					(size 1.27 1.27)
				)
			)
		)
		(property "Value" ""
			(at 0 0 180)
			(layer "F.Fab")
			(effects
				(font
					(size 1.27 1.27)
				)
			)
		)
		(duplicate_pad_numbers_are_jumpers no)
		(fp_line
			(start 0.7874 0.4064)
			(end -0.7874 0.4064)
			(stroke
				(width 0.1524)
				(type default)
			)
			(layer "F.SilkS")
		)
		(fp_line
			(start 0.7874 -0.4064)
			(end 0.7874 0.4064)
			(stroke
				(width 0.1524)
				(type default)
			)
			(layer "F.SilkS")
		)
		(fp_line
			(start -0.7874 0.4064)
			(end -0.7874 -0.4064)
			(stroke
				(width 0.1524)
				(type default)
			)
			(layer "F.SilkS")
		)
		(fp_line
			(start -0.7874 -0.4064)
			(end 0.7874 -0.4064)
			(stroke
				(width 0.1524)
				(type default)
			)
			(layer "F.SilkS")
		)
		(fp_line
			(start 0.67945 0.3048)
			(end 0.120396 0.3048)
			(stroke
				(width 0.1)
				(type default)
			)
			(layer "F.Fab")
		)
		(fp_line
			(start 0.67945 -0.3048)
			(end 0.67945 0.3048)
			(stroke
				(width 0.1)
				(type default)
			)
			(layer "F.Fab")
		)
		(fp_line
			(start 0.12065 -0.2794)
			(end 0.12065 -0.3048)
			(stroke
				(width 0.1)
				(type default)
			)
			(layer "F.Fab")
		)
		(fp_line
			(start 0.12065 -0.3048)
			(end 0.67945 -0.3048)
			(stroke
				(width 0.1)
				(type default)
			)
			(layer "F.Fab")
		)
		(fp_line
			(start 0.120396 0.3048)
			(end 0.120396 0.2794)
			(stroke
				(width 0.1)
				(type default)
			)
			(layer "F.Fab")
		)
		(fp_line
			(start 0.120396 0.2794)
			(end -0.12065 0.2794)
			(stroke
				(width 0.1)
				(type default)
			)
			(layer "F.Fab")
		)
		(fp_line
			(start -0.12065 0.3048)
			(end -0.67945 0.3048)
			(stroke
				(width 0.1)
				(type default)
			)
			(layer "F.Fab")
		)
		(fp_line
			(start -0.12065 0.2794)
			(end -0.12065 0.3048)
			(stroke
				(width 0.1)
				(type default)
			)
			(layer "F.Fab")
		)
		(fp_line
			(start -0.12065 -0.2794)
			(end 0.12065 -0.2794)
			(stroke
				(width 0.1)
				(type default)
			)
			(layer "F.Fab")
		)
		(fp_line
			(start -0.12065 -0.305054)
			(end -0.12065 -0.2794)
			(stroke
				(width 0.1)
				(type default)
			)
			(layer "F.Fab")
		)
		(fp_line
			(start -0.67945 0.3048)
			(end -0.67945 -0.305054)
			(stroke
				(width 0.1)
				(type default)
			)
			(layer "F.Fab")
		)
		(fp_line
			(start -0.67945 -0.305054)
			(end -0.12065 -0.305054)
			(stroke
				(width 0.1)
				(type default)
			)
			(layer "F.Fab")
		)
		(pad "1" smd rect
			(at -0.40005 0)
			(size 0.4572 0.508)
			(layers "F.Cu" "F.Mask" "F.Paste")
			(net "P1V581_PDB_ADC")
		)
		(pad "2" smd rect
			(at 0.40005 0)
			(size 0.4572 0.508)
			(layers "F.Cu" "F.Mask" "F.Paste")
			(net "P3V3_PDB_AUX_ADC_TIC")
		)
	)
	(footprint ""
		(layer "F.Cu")
		(at 355.616002 -256.012188 90)
		(property "Reference" "C2562"
			(at 0 0 90)
			(layer "F.SilkS")
			(hide yes)
			(effects
				(font
					(size 1.27 1.27)
				)
			)
		)
		(property "Value" ""
			(at 0 0 90)
			(layer "F.Fab")
			(effects
				(font
					(size 1.27 1.27)
				)
			)
		)
		(duplicate_pad_numbers_are_jumpers no)
		(fp_line
			(start 0.7874 -0.4064)
			(end 0.7874 0.4064)
			(stroke
				(width 0.1524)
				(type default)
			)
			(layer "F.SilkS")
		)
		(fp_line
			(start -0.7874 -0.4064)
			(end 0.7874 -0.4064)
			(stroke
				(width 0.1524)
				(type default)
			)
			(layer "F.SilkS")
		)
		(fp_line
			(start 0.7874 0.4064)
			(end -0.7874 0.4064)
			(stroke
				(width 0.1524)
				(type default)
			)
			(layer "F.SilkS")
		)
		(fp_line
			(start -0.7874 0.4064)
			(end -0.7874 -0.4064)
			(stroke
				(width 0.1524)
				(type default)
			)
			(layer "F.SilkS")
		)
		(fp_line
			(start -0.12065 -0.305054)
			(end -0.12065 -0.2794)
			(stroke
				(width 0.1)
				(type default)
			)
			(layer "F.Fab")
		)
		(fp_line
			(start -0.67945 -0.305054)
			(end -0.12065 -0.305054)
			(stroke
				(width 0.1)
				(type default)
			)
			(layer "F.Fab")
		)
		(fp_line
			(start 0.67945 -0.3048)
			(end 0.67945 0.3048)
			(stroke
				(width 0.1)
				(type default)
			)
			(layer "F.Fab")
		)
		(fp_line
			(start 0.12065 -0.3048)
			(end 0.67945 -0.3048)
			(stroke
				(width 0.1)
				(type default)
			)
			(layer "F.Fab")
		)
		(fp_line
			(start 0.12065 -0.2794)
			(end 0.12065 -0.3048)
			(stroke
				(width 0.1)
				(type default)
			)
			(layer "F.Fab")
		)
		(fp_line
			(start -0.12065 -0.2794)
			(end 0.12065 -0.2794)
			(stroke
				(width 0.1)
				(type default)
			)
			(layer "F.Fab")
		)
		(fp_line
			(start 0.120396 0.2794)
			(end -0.12065 0.2794)
			(stroke
				(width 0.1)
				(type default)
			)
			(layer "F.Fab")
		)
		(fp_line
			(start -0.12065 0.2794)
			(end -0.12065 0.3048)
			(stroke
				(width 0.1)
				(type default)
			)
			(layer "F.Fab")
		)
		(fp_line
			(start 0.67945 0.3048)
			(end 0.120396 0.3048)
			(stroke
				(width 0.1)
				(type default)
			)
			(layer "F.Fab")
		)
		(fp_line
			(start 0.120396 0.3048)
			(end 0.120396 0.2794)
			(stroke
				(width 0.1)
				(type default)
			)
			(layer "F.Fab")
		)
		(fp_line
			(start -0.12065 0.3048)
			(end -0.67945 0.3048)
			(stroke
				(width 0.1)
				(type default)
			)
			(layer "F.Fab")
		)
		(fp_line
			(start -0.67945 0.3048)
			(end -0.67945 -0.305054)
			(stroke
				(width 0.1)
				(type default)
			)
			(layer "F.Fab")
		)
		(pad "1" smd circle
			(at -0.40005 0 90)
			(size 0 0)
			(layers "F.Cu" "F.Mask" "F.Paste")
			(net "PVDDCR_SOC_P0")
		)
		(pad "2" smd circle
			(at 0.40005 0 90)
			(size 0 0)
			(layers "F.Cu" "F.Mask" "F.Paste")
			(net "GND")
		)
	)
)
